# S9S_MB_2U (Grand Teton) — schematic netlist excerpt (pin names and nets, part order shuffled) for the footprints in the layout excerpt that follows; sources: Cadence DE-HDL packaged netlist, KiCad conversion of 03242023_DA0F0TMBIJ0_F0T_Motherboard_J_brd_V01_OCP.brd

PR298  Q_RES  8.87K 1% EMPTY  pkg 0402LF  page 286 : A = PVCCIN_CPU1_LSET3 ; B = GND

(kicad_pcb
	(version 20260206)
	(generator "pcbnew")
	(generator_version "10.0")
	(general
		(thickness 1.6)
		(legacy_teardrops no)
	)
	(paper "A4")
	(title_block
		(title "03242023_DA0F0TMBIJ0_F0T_Motherboard_J_brd_V01_OCP.brd")
		(comment 1 "Grand Teton / footprints 1353-1353 of 6105")
	)
	(layers
		(0 "F.Cu" signal "TOP")
		(4 "In1.Cu" signal "GND")
		(6 "In2.Cu" signal "IN1")
		(8 "In3.Cu" signal "GND1")
		(10 "In4.Cu" signal "IN2")
		(12 "In5.Cu" signal "GND2")
		(14 "In6.Cu" signal "IN3")
		(16 "In7.Cu" signal "GND3")
		(18 "In8.Cu" signal "VCC")
		(20 "In9.Cu" signal "VCC1")
		(22 "In10.Cu" signal "GND4")
		(24 "In11.Cu" signal "IN4")
		(26 "In12.Cu" signal "GND5")
		(28 "In13.Cu" signal "IN5")
		(30 "In14.Cu" signal "GND6")
		(32 "In15.Cu" signal "IN6")
		(34 "In16.Cu" signal "GND7")
		(2 "B.Cu" signal "BOTTOM")
		(9 "F.Adhes" user "F.Adhesive")
		(11 "B.Adhes" user "B.Adhesive")
		(13 "F.Paste" user "Package Geometry/Pastemask Top")
		(15 "B.Paste" user "Package Geometry/Pastemask Bottom")
		(5 "F.SilkS" user "Ref Des/Silkscreen Top")
		(7 "B.SilkS" user "Ref Des/Silkscreen Bottom")
		(1 "F.Mask" user "Board Geometry/Soldermask Top")
		(3 "B.Mask" user "Board Geometry/Soldermask Bottom")
		(17 "Dwgs.User" user "User.Drawings")
		(19 "Cmts.User" user "User.Comments")
		(21 "Eco1.User" user "User.Eco1")
		(23 "Eco2.User" user "User.Eco2")
		(25 "Edge.Cuts" user "Board Geometry/Outline")
		(27 "Margin" user)
		(31 "F.CrtYd" user "Package Geometry/Place Bound Top")
		(29 "B.CrtYd" user "Package Geometry/Place Bound Bottom")
		(35 "F.Fab" user "Ref Des/Assembly Top")
		(33 "B.Fab" user "Ref Des/Assembly Bottom")
	)
	(footprint ""
		(layer "F.Cu")
		(at 112.027462 -338.86013)
		(property "Reference" "PR298"
			(at 0 0 0)
			(layer "F.SilkS")
			(hide yes)
			(effects
				(font
					(size 1.27 1.27)
				)
			)
		)
		(property "Value" ""
			(at 0 0 0)
			(layer "F.Fab")
			(effects
				(font
					(size 1.27 1.27)
				)
			)
		)
		(duplicate_pad_numbers_are_jumpers no)
		(fp_line
			(start -0.7874 -0.4064)
			(end 0.7874 -0.4064)
			(stroke
				(width 0.1524)
				(type default)
			)
			(layer "F.SilkS")
		)
		(fp_line
			(start -0.7874 0.4064)
			(end -0.7874 -0.4064)
			(stroke
				(width 0.1524)
				(type default)
			)
			(layer "F.SilkS")
		)
		(fp_line
			(start 0.7874 -0.4064)
			(end 0.7874 0.4064)
			(stroke
				(width 0.1524)
				(type default)
			)
			(layer "F.SilkS")
		)
		(fp_line
			(start 0.7874 0.4064)
			(end -0.7874 0.4064)
			(stroke
				(width 0.1524)
				(type default)
			)
			(layer "F.SilkS")
		)
		(fp_line
			(start -0.67945 -0.305054)
			(end -0.12065 -0.305054)
			(stroke
				(width 0.1)
				(type default)
			)
			(layer "F.Fab")
		)
		(fp_line
			(start -0.67945 0.3048)
			(end -0.67945 -0.305054)
			(stroke
				(width 0.1)
				(type default)
			)
			(layer "F.Fab")
		)
		(fp_line
			(start -0.12065 -0.305054)
			(end -0.12065 -0.2794)
			(stroke
				(width 0.1)
				(type default)
			)
			(layer "F.Fab")
		)
		(fp_line
			(start -0.12065 -0.2794)
			(end 0.12065 -0.2794)
			(stroke
				(width 0.1)
				(type default)
			)
			(layer "F.Fab")
		)
		(fp_line
			(start -0.12065 0.2794)
			(end -0.12065 0.3048)
			(stroke
				(width 0.1)
				(type default)
			)
			(layer "F.Fab")
		)
		(fp_line
			(start -0.12065 0.3048)
			(end -0.67945 0.3048)
			(stroke
				(width 0.1)
				(type default)
			)
			(layer "F.Fab")
		)
		(fp_line
			(start 0.120396 0.2794)
			(end -0.12065 0.2794)
			(stroke
				(width 0.1)
				(type default)
			)
			(layer "F.Fab")
		)
		(fp_line
			(start 0.120396 0.3048)
			(end 0.120396 0.2794)
			(stroke
				(width 0.1)
				(type default)
			)
			(layer "F.Fab")
		)
		(fp_line
			(start 0.12065 -0.3048)
			(end 0.67945 -0.3048)
			(stroke
				(width 0.1)
				(type default)
			)
			(layer "F.Fab")
		)
		(fp_line
			(start 0.12065 -0.2794)
			(end 0.12065 -0.3048)
			(stroke
				(width 0.1)
				(type default)
			)
			(layer "F.Fab")
		)
		(fp_line
			(start 0.67945 -0.3048)
			(end 0.67945 0.3048)
			(stroke
				(width 0.1)
				(type default)
			)
			(layer "F.Fab")
		)
		(fp_line
			(start 0.67945 0.3048)
			(end 0.120396 0.3048)
			(stroke
				(width 0.1)
				(type default)
			)
			(layer "F.Fab")
		)
		(pad "1" smd circle
			(at -0.40005 0)
			(size 0 0)
			(layers "F.Cu" "F.Mask" "F.Paste")
			(net "PVCCIN_CPU1_LSET3")
		)
		(pad "2" smd circle
			(at 0.40005 0)
			(size 0 0)
			(layers "F.Cu" "F.Mask" "F.Paste")
			(net "GND")
		)
	)
)
